(kicad_pcb
	(version 20260206)
	(generator "pcbnew")
	(generator_version "10.0")
	(general
		(thickness 1.6)
		(legacy_teardrops no)
	)
	(paper "A4")
	(title_block
		(title "pdpb — Lightning_PDPB_BRD.brd")
		(comment 1 "Lightning (Wiwynn / Facebook NVMe JBOF) / footprints 464-470 of 1140")
	)
	(layers
		(0 "F.Cu" signal "TOP")
		(4 "In1.Cu" signal "L2GND")
		(6 "In2.Cu" signal "L3")
		(8 "In3.Cu" signal "L4VCC")
		(10 "In4.Cu" signal "L5VCC")
		(12 "In5.Cu" signal "L6")
		(14 "In6.Cu" signal "L7GND")
		(2 "B.Cu" signal "BOTTOM")
		(9 "F.Adhes" user "F.Adhesive")
		(11 "B.Adhes" user "B.Adhesive")
		(13 "F.Paste" user "Package Geometry/Pastemask Top")
		(15 "B.Paste" user "Package Geometry/Pastemask Bottom")
		(5 "F.SilkS" user "Ref Des/Silkscreen Top")
		(7 "B.SilkS" user "Ref Des/Silkscreen Bottom")
		(1 "F.Mask" user "Board Geometry/Soldermask Top")
		(3 "B.Mask" user "Board Geometry/Soldermask Bottom")
		(17 "Dwgs.User" user "User.Drawings")
		(19 "Cmts.User" user "User.Comments")
		(21 "Eco1.User" user "User.Eco1")
		(23 "Eco2.User" user "User.Eco2")
		(25 "Edge.Cuts" user "Board Geometry/Outline")
		(27 "Margin" user)
		(31 "F.CrtYd" user "Package Geometry/Place Bound Top")
		(29 "B.CrtYd" user "Package Geometry/Place Bound Bottom")
		(35 "F.Fab" user "Ref Des/Assembly Top")
		(33 "B.Fab" user "Ref Des/Assembly Bottom")
	)
	(footprint ""
		(layer "F.Cu")
		(at 20.3835 -163.887658 -90)
		(property "Reference" "SR1148"
			(at 0 0 270)
			(layer "F.SilkS")
			(hide yes)
			(effects
				(font
					(size 1.27 1.27)
				)
			)
		)
		(property "Value" "4K7R2J-2-GP"
			(at 0.064008 -3.993896 270)
			(unlocked yes)
			(layer "F.Fab")
			(hide yes)
			(effects
				(font
					(size 1.016 1.016)
					(thickness 0.1524)
				)
			)
		)
		(property "Device Type" "R402H16"
			(at 0.064008 -5.517896 270)
			(unlocked yes)
			(layer "F.Fab")
			(hide yes)
			(effects
				(font
					(size 1.016 1.016)
					(thickness 0.1524)
				)
			)
		)
		(duplicate_pad_numbers_are_jumpers no)
		(fp_line
			(start -0.508 -0.9398)
			(end -0.508 0.9398)
			(stroke
				(width 0.1524)
				(type default)
			)
			(layer "F.SilkS")
		)
		(fp_line
			(start 0.508 -0.9398)
			(end -0.508 -0.9398)
			(stroke
				(width 0.1524)
				(type default)
			)
			(layer "F.SilkS")
		)
		(fp_rect
			(start -0.508 0.9398)
			(end 0.508 -0.9398)
			(stroke
				(width 0)
				(type default)
			)
			(fill no)
			(layer "F.CrtYd")
		)
		(fp_rect
			(start -0.508 0.9398)
			(end 0.508 -0.9398)
			(stroke
				(width 0)
				(type default)
			)
			(fill no)
			(layer "F.Fab")
		)
		(pad "1" smd custom
			(at 0 -0.4445 270)
			(size 0.1397 0.1397)
			(layers "F.Cu" "F.Mask" "F.Paste")
			(net "P3V3")
			(options
				(clearance outline)
				(anchor circle)
			)
			(primitives
				(gr_poly
					(pts
						(arc
							(start -0.1778 -0.2794)
							(mid -0.249642 -0.249642)
							(end -0.2794 -0.1778)
						)
						(arc
							(start -0.2794 0.1778)
							(mid -0.249642 0.249642)
							(end -0.1778 0.2794)
						)
						(arc
							(start 0.1778 0.2794)
							(mid 0.249642 0.249642)
							(end 0.2794 0.1778)
						)
						(arc
							(start 0.2794 -0.1778)
							(mid 0.249642 -0.249642)
							(end 0.1778 -0.2794)
						)
					)
					(width 0)
					(fill yes)
				)
			)
		)
		(pad "2" smd custom
			(at 0 0.4445 270)
			(size 0.1397 0.1397)
			(layers "F.Cu" "F.Mask" "F.Paste")
			(net "SSD_ACT_DR13")
			(options
				(clearance outline)
				(anchor circle)
			)
			(primitives
				(gr_poly
					(pts
						(arc
							(start -0.1778 -0.2794)
							(mid -0.249642 -0.249642)
							(end -0.2794 -0.1778)
						)
						(arc
							(start -0.2794 0.1778)
							(mid -0.249642 0.249642)
							(end -0.1778 0.2794)
						)
						(arc
							(start 0.1778 0.2794)
							(mid 0.249642 0.249642)
							(end 0.2794 0.1778)
						)
						(arc
							(start 0.2794 -0.1778)
							(mid 0.249642 -0.249642)
							(end 0.1778 -0.2794)
						)
					)
					(width 0)
					(fill yes)
				)
			)
		)
	)
	(footprint ""
		(layer "F.Cu")
		(at 108.966 -310.261)
		(property "Reference" "R9492"
			(at 0 0 0)
			(layer "F.SilkS")
			(hide yes)
			(effects
				(font
					(size 1.27 1.27)
				)
			)
		)
		(property "Value" "4K7R2J-2-GP"
			(at 0.064008 -3.993896 0)
			(unlocked yes)
			(layer "F.Fab")
			(hide yes)
			(effects
				(font
					(size 1.016 1.016)
					(thickness 0.1524)
				)
			)
		)
		(property "Device Type" "R402H16"
			(at 0.064008 -5.517896 0)
			(unlocked yes)
			(layer "F.Fab")
			(hide yes)
			(effects
				(font
					(size 1.016 1.016)
					(thickness 0.1524)
				)
			)
		)
		(duplicate_pad_numbers_are_jumpers no)
		(fp_line
			(start -0.508 -0.9398)
			(end -0.508 0.9398)
			(stroke
				(width 0.1524)
				(type default)
			)
			(layer "F.SilkS")
		)
		(fp_line
			(start 0.508 -0.9398)
			(end -0.508 -0.9398)
			(stroke
				(width 0.1524)
				(type default)
			)
			(layer "F.SilkS")
		)
		(fp_rect
			(start -0.508 0.9398)
			(end 0.508 -0.9398)
			(stroke
				(width 0)
				(type default)
			)
			(fill no)
			(layer "F.CrtYd")
		)
		(fp_rect
			(start -0.508 0.9398)
			(end 0.508 -0.9398)
			(stroke
				(width 0)
				(type default)
			)
			(fill no)
			(layer "F.Fab")
		)
		(pad "1" smd custom
			(at 0 -0.4445)
			(size 0.1397 0.1397)
			(layers "F.Cu" "F.Mask" "F.Paste")
			(net "P3V3")
			(options
				(clearance outline)
				(anchor circle)
			)
			(primitives
				(gr_poly
					(pts
						(arc
							(start -0.1778 -0.2794)
							(mid -0.249642 -0.249642)
							(end -0.2794 -0.1778)
						)
						(arc
							(start -0.2794 0.1778)
							(mid -0.249642 0.249642)
							(end -0.1778 0.2794)
						)
						(arc
							(start 0.1778 0.2794)
							(mid 0.249642 0.249642)
							(end 0.2794 0.1778)
						)
						(arc
							(start 0.2794 -0.1778)
							(mid 0.249642 -0.249642)
							(end 0.1778 -0.2794)
						)
					)
					(width 0)
					(fill yes)
				)
			)
		)
		(pad "2" smd custom
			(at 0 0.4445)
			(size 0.1397 0.1397)
			(layers "F.Cu" "F.Mask" "F.Paste")
			(net "SSD1_CLK0_OE_N")
			(options
				(clearance outline)
				(anchor circle)
			)
			(primitives
				(gr_poly
					(pts
						(arc
							(start -0.1778 -0.2794)
							(mid -0.249642 -0.249642)
							(end -0.2794 -0.1778)
						)
						(arc
							(start -0.2794 0.1778)
							(mid -0.249642 0.249642)
							(end -0.1778 0.2794)
						)
						(arc
							(start 0.1778 0.2794)
							(mid 0.249642 0.249642)
							(end 0.2794 0.1778)
						)
						(arc
							(start 0.2794 -0.1778)
							(mid 0.249642 -0.249642)
							(end 0.1778 -0.2794)
						)
					)
					(width 0)
					(fill yes)
				)
			)
		)
	)
	(footprint ""
		(layer "F.Cu")
		(at 210.312 -293.116)
		(property "Reference" "C384"
			(at 0 0 0)
			(layer "F.SilkS")
			(hide yes)
			(effects
				(font
					(size 1.27 1.27)
				)
			)
		)
		(property "Value" "SCD1U25V2KX-2-GP"
			(at 1.1811 -2.7051 0)
			(unlocked yes)
			(layer "F.Fab")
			(hide yes)
			(effects
				(font
					(size 1.016 1.016)
					(thickness 0.1524)
				)
			)
		)
		(property "Device Type" "C402H22"
			(at 1.1811 -4.2291 0)
			(unlocked yes)
			(layer "F.Fab")
			(hide yes)
			(effects
				(font
					(size 1.016 1.016)
					(thickness 0.1524)
				)
			)
		)
		(duplicate_pad_numbers_are_jumpers no)
		(fp_rect
			(start -0.4318 0.9525)
			(end 0.4318 -0.9525)
			(stroke
				(width 0)
				(type default)
			)
			(fill no)
			(layer "F.CrtYd")
		)
		(fp_rect
			(start -0.4318 0.9525)
			(end 0.4318 -0.9525)
			(stroke
				(width 0)
				(type default)
			)
			(fill no)
			(layer "F.Fab")
		)
		(pad "1" smd custom
			(at 0 -0.4445)
			(size 0.1524 0.1524)
			(layers "F.Cu" "F.Mask" "F.Paste")
			(net "P12V")
			(options
				(clearance outline)
				(anchor circle)
			)
			(primitives
				(gr_poly
					(pts
						(arc
							(start 0.3048 -0.2032)
							(mid 0.275042 -0.275042)
							(end 0.2032 -0.3048)
						)
						(arc
							(start -0.2032 -0.3048)
							(mid -0.275042 -0.275042)
							(end -0.3048 -0.2032)
						)
						(arc
							(start -0.3048 0.2032)
							(mid -0.275042 0.275042)
							(end -0.2032 0.3048)
						)
						(arc
							(start 0.2032 0.3048)
							(mid 0.275042 0.275042)
							(end 0.3048 0.2032)
						)
					)
					(width 0)
					(fill yes)
				)
			)
		)
		(pad "2" smd custom
			(at 0 0.4445)
			(size 0.1524 0.1524)
			(layers "F.Cu" "F.Mask" "F.Paste")
			(net "SW_SSD2_N")
			(options
				(clearance outline)
				(anchor circle)
			)
			(primitives
				(gr_poly
					(pts
						(arc
							(start 0.3048 -0.2032)
							(mid 0.275042 -0.275042)
							(end 0.2032 -0.3048)
						)
						(arc
							(start -0.2032 -0.3048)
							(mid -0.275042 -0.275042)
							(end -0.3048 -0.2032)
						)
						(arc
							(start -0.3048 0.2032)
							(mid -0.275042 0.275042)
							(end -0.2032 0.3048)
						)
						(arc
							(start 0.2032 0.3048)
							(mid 0.275042 0.275042)
							(end 0.3048 0.2032)
						)
					)
					(width 0)
					(fill yes)
				)
			)
		)
	)
	(footprint ""
		(layer "F.Cu")
		(at 78.5622 -303.7205 180)
		(property "Reference" "R9962"
			(at 0 0 180)
			(layer "F.SilkS")
			(hide yes)
			(effects
				(font
					(size 1.27 1.27)
				)
			)
		)
		(property "Value" "470R2F-GP"
			(at 0.064008 -3.993896 180)
			(unlocked yes)
			(layer "F.Fab")
			(hide yes)
			(effects
				(font
					(size 1.016 1.016)
					(thickness 0.1524)
				)
			)
		)
		(property "Device Type" "R402H16"
			(at 0.064008 -5.517896 180)
			(unlocked yes)
			(layer "F.Fab")
			(hide yes)
			(effects
				(font
					(size 1.016 1.016)
					(thickness 0.1524)
				)
			)
		)
		(duplicate_pad_numbers_are_jumpers no)
		(fp_line
			(start 0.508 -0.9398)
			(end -0.508 -0.9398)
			(stroke
				(width 0.1524)
				(type default)
			)
			(layer "F.SilkS")
		)
		(fp_line
			(start -0.508 -0.9398)
			(end -0.508 0.9398)
			(stroke
				(width 0.1524)
				(type default)
			)
			(layer "F.SilkS")
		)
		(fp_rect
			(start -0.508 0.9398)
			(end 0.508 -0.9398)
			(stroke
				(width 0)
				(type default)
			)
			(fill no)
			(layer "F.CrtYd")
		)
		(fp_rect
			(start -0.508 0.9398)
			(end 0.508 -0.9398)
			(stroke
				(width 0)
				(type default)
			)
			(fill no)
			(layer "F.Fab")
		)
		(pad "1" smd custom
			(at 0 -0.4445 180)
			(size 0.1397 0.1397)
			(layers "F.Cu" "F.Mask" "F.Paste")
			(net "VDD_DIFF_2")
			(options
				(clearance outline)
				(anchor circle)
			)
			(primitives
				(gr_poly
					(pts
						(arc
							(start -0.1778 -0.2794)
							(mid -0.249642 -0.249642)
							(end -0.2794 -0.1778)
						)
						(arc
							(start -0.2794 0.1778)
							(mid -0.249642 0.249642)
							(end -0.1778 0.2794)
						)
						(arc
							(start 0.1778 0.2794)
							(mid 0.249642 0.249642)
							(end 0.2794 0.1778)
						)
						(arc
							(start 0.2794 -0.1778)
							(mid 0.249642 -0.249642)
							(end 0.1778 -0.2794)
						)
					)
					(width 0)
					(fill yes)
				)
			)
		)
		(pad "2" smd custom
			(at 0 0.4445 180)
			(size 0.1397 0.1397)
			(layers "F.Cu" "F.Mask" "F.Paste")
			(net "PE_100M_CLK3_N")
			(options
				(clearance outline)
				(anchor circle)
			)
			(primitives
				(gr_poly
					(pts
						(arc
							(start -0.1778 -0.2794)
							(mid -0.249642 -0.249642)
							(end -0.2794 -0.1778)
						)
						(arc
							(start -0.2794 0.1778)
							(mid -0.249642 0.249642)
							(end -0.1778 0.2794)
						)
						(arc
							(start 0.1778 0.2794)
							(mid 0.249642 0.249642)
							(end 0.2794 0.1778)
						)
						(arc
							(start 0.2794 -0.1778)
							(mid 0.249642 -0.249642)
							(end 0.1778 -0.2794)
						)
					)
					(width 0)
					(fill yes)
				)
			)
		)
	)
	(footprint ""
		(layer "F.Cu")
		(at 234.061 -445.008 90)
		(property "Reference" "R9781"
			(at 0 0 90)
			(layer "F.SilkS")
			(hide yes)
			(effects
				(font
					(size 1.27 1.27)
				)
			)
		)
		(property "Value" "0R2J-2-GP"
			(at 0.064008 -3.993896 90)
			(unlocked yes)
			(layer "F.Fab")
			(hide yes)
			(effects
				(font
					(size 1.016 1.016)
					(thickness 0.1524)
				)
			)
		)
		(property "Device Type" "R402H16"
			(at 0.064008 -5.517896 90)
			(unlocked yes)
			(layer "F.Fab")
			(hide yes)
			(effects
				(font
					(size 1.016 1.016)
					(thickness 0.1524)
				)
			)
		)
		(duplicate_pad_numbers_are_jumpers no)
		(fp_line
			(start 0.508 -0.9398)
			(end -0.508 -0.9398)
			(stroke
				(width 0.1524)
				(type default)
			)
			(layer "F.SilkS")
		)
		(fp_line
			(start -0.508 -0.9398)
			(end -0.508 0.9398)
			(stroke
				(width 0.1524)
				(type default)
			)
			(layer "F.SilkS")
		)
		(fp_rect
			(start -0.508 0.9398)
			(end 0.508 -0.9398)
			(stroke
				(width 0)
				(type default)
			)
			(fill no)
			(layer "F.CrtYd")
		)
		(fp_rect
			(start -0.508 0.9398)
			(end 0.508 -0.9398)
			(stroke
				(width 0)
				(type default)
			)
			(fill no)
			(layer "F.Fab")
		)
		(pad "1" smd custom
			(at 0 -0.4445 90)
			(size 0.1397 0.1397)
			(layers "F.Cu" "F.Mask" "F.Paste")
			(net "ATTN_LED_DR0_AND")
			(options
				(clearance outline)
				(anchor circle)
			)
			(primitives
				(gr_poly
					(pts
						(arc
							(start -0.1778 -0.2794)
							(mid -0.249642 -0.249642)
							(end -0.2794 -0.1778)
						)
						(arc
							(start -0.2794 0.1778)
							(mid -0.249642 0.249642)
							(end -0.1778 0.2794)
						)
						(arc
							(start 0.1778 0.2794)
							(mid 0.249642 0.249642)
							(end 0.2794 0.1778)
						)
						(arc
							(start 0.2794 -0.1778)
							(mid 0.249642 -0.249642)
							(end 0.1778 -0.2794)
						)
					)
					(width 0)
					(fill yes)
				)
			)
		)
		(pad "2" smd custom
			(at 0 0.4445 90)
			(size 0.1397 0.1397)
			(layers "F.Cu" "F.Mask" "F.Paste")
			(net "ATTN_LED_DR0_AND_R")
			(options
				(clearance outline)
				(anchor circle)
			)
			(primitives
				(gr_poly
					(pts
						(arc
							(start -0.1778 -0.2794)
							(mid -0.249642 -0.249642)
							(end -0.2794 -0.1778)
						)
						(arc
							(start -0.2794 0.1778)
							(mid -0.249642 0.249642)
							(end -0.1778 0.2794)
						)
						(arc
							(start 0.1778 0.2794)
							(mid 0.249642 0.249642)
							(end 0.2794 0.1778)
						)
						(arc
							(start 0.2794 -0.1778)
							(mid 0.249642 -0.249642)
							(end 0.1778 -0.2794)
						)
					)
					(width 0)
					(fill yes)
				)
			)
		)
	)
	(footprint ""
		(layer "F.Cu")
		(at 38.8366 -212.8774 180)
		(property "Reference" "R563"
			(at 0 0 180)
			(layer "F.SilkS")
			(hide yes)
			(effects
				(font
					(size 1.27 1.27)
				)
			)
		)
		(property "Value" "200KR2F-L-GP"
			(at 0.064008 -3.993896 180)
			(unlocked yes)
			(layer "F.Fab")
			(hide yes)
			(effects
				(font
					(size 1.016 1.016)
					(thickness 0.1524)
				)
			)
		)
		(property "Device Type" "R402H16"
			(at 0.064008 -5.517896 180)
			(unlocked yes)
			(layer "F.Fab")
			(hide yes)
			(effects
				(font
					(size 1.016 1.016)
					(thickness 0.1524)
				)
			)
		)
		(duplicate_pad_numbers_are_jumpers no)
		(fp_line
			(start 0.508 -0.9398)
			(end -0.508 -0.9398)
			(stroke
				(width 0.1524)
				(type default)
			)
			(layer "F.SilkS")
		)
		(fp_line
			(start -0.508 -0.9398)
			(end -0.508 0.9398)
			(stroke
				(width 0.1524)
				(type default)
			)
			(layer "F.SilkS")
		)
		(fp_rect
			(start -0.508 0.9398)
			(end 0.508 -0.9398)
			(stroke
				(width 0)
				(type default)
			)
			(fill no)
			(layer "F.CrtYd")
		)
		(fp_rect
			(start -0.508 0.9398)
			(end 0.508 -0.9398)
			(stroke
				(width 0)
				(type default)
			)
			(fill no)
			(layer "F.Fab")
		)
		(pad "1" smd custom
			(at 0 -0.4445 180)
			(size 0.1397 0.1397)
			(layers "F.Cu" "F.Mask" "F.Paste")
			(net "SW_SSD12_R")
			(options
				(clearance outline)
				(anchor circle)
			)
			(primitives
				(gr_poly
					(pts
						(arc
							(start -0.1778 -0.2794)
							(mid -0.249642 -0.249642)
							(end -0.2794 -0.1778)
						)
						(arc
							(start -0.2794 0.1778)
							(mid -0.249642 0.249642)
							(end -0.1778 0.2794)
						)
						(arc
							(start 0.1778 0.2794)
							(mid 0.249642 0.249642)
							(end 0.2794 0.1778)
						)
						(arc
							(start 0.2794 -0.1778)
							(mid 0.249642 -0.249642)
							(end 0.1778 -0.2794)
						)
					)
					(width 0)
					(fill yes)
				)
			)
		)
		(pad "2" smd custom
			(at 0 0.4445 180)
			(size 0.1397 0.1397)
			(layers "F.Cu" "F.Mask" "F.Paste")
			(net "SW_SSD12_N")
			(options
				(clearance outline)
				(anchor circle)
			)
			(primitives
				(gr_poly
					(pts
						(arc
							(start -0.1778 -0.2794)
							(mid -0.249642 -0.249642)
							(end -0.2794 -0.1778)
						)
						(arc
							(start -0.2794 0.1778)
							(mid -0.249642 0.249642)
							(end -0.1778 0.2794)
						)
						(arc
							(start 0.1778 0.2794)
							(mid 0.249642 0.249642)
							(end 0.2794 0.1778)
						)
						(arc
							(start 0.2794 -0.1778)
							(mid 0.249642 -0.249642)
							(end 0.1778 -0.2794)
						)
					)
					(width 0)
					(fill yes)
				)
			)
		)
	)
	(footprint ""
		(layer "F.Cu")
		(at 77.216 -154.178)
		(property "Reference" "SR974"
			(at 0 0 0)
			(layer "F.SilkS")
			(hide yes)
			(effects
				(font
					(size 1.27 1.27)
				)
			)
		)
		(property "Value" "2KR2F-3-GP"
			(at 0.064008 -3.993896 0)
			(unlocked yes)
			(layer "F.Fab")
			(hide yes)
			(effects
				(font
					(size 1.016 1.016)
					(thickness 0.1524)
				)
			)
		)
		(property "Device Type" "R402H16"
			(at 0.064008 -5.517896 0)
			(unlocked yes)
			(layer "F.Fab")
			(hide yes)
			(effects
				(font
					(size 1.016 1.016)
					(thickness 0.1524)
				)
			)
		)
		(duplicate_pad_numbers_are_jumpers no)
		(fp_line
			(start -0.508 -0.9398)
			(end -0.508 0.9398)
			(stroke
				(width 0.1524)
				(type default)
			)
			(layer "F.SilkS")
		)
		(fp_line
			(start 0.508 -0.9398)
			(end -0.508 -0.9398)
			(stroke
				(width 0.1524)
				(type default)
			)
			(layer "F.SilkS")
		)
		(fp_rect
			(start -0.508 0.9398)
			(end 0.508 -0.9398)
			(stroke
				(width 0)
				(type default)
			)
			(fill no)
			(layer "F.CrtYd")
		)
		(fp_rect
			(start -0.508 0.9398)
			(end 0.508 -0.9398)
			(stroke
				(width 0)
				(type default)
			)
			(fill no)
			(layer "F.Fab")
		)
		(pad "1" smd custom
			(at 0 -0.4445)
			(size 0.1397 0.1397)
			(layers "F.Cu" "F.Mask" "F.Paste")
			(net "P3V3")
			(options
				(clearance outline)
				(anchor circle)
			)
			(primitives
				(gr_poly
					(pts
						(arc
							(start -0.1778 -0.2794)
							(mid -0.249642 -0.249642)
							(end -0.2794 -0.1778)
						)
						(arc
							(start -0.2794 0.1778)
							(mid -0.249642 0.249642)
							(end -0.1778 0.2794)
						)
						(arc
							(start 0.1778 0.2794)
							(mid 0.249642 0.249642)
							(end 0.2794 0.1778)
						)
						(arc
							(start 0.2794 -0.1778)
							(mid 0.249642 -0.249642)
							(end 0.1778 -0.2794)
						)
					)
					(width 0)
					(fill yes)
				)
			)
		)
		(pad "2" smd custom
			(at 0 0.4445)
			(size 0.1397 0.1397)
			(layers "F.Cu" "F.Mask" "F.Paste")
			(net "SDA_DR4")
			(options
				(clearance outline)
				(anchor circle)
			)
			(primitives
				(gr_poly
					(pts
						(arc
							(start -0.1778 -0.2794)
							(mid -0.249642 -0.249642)
							(end -0.2794 -0.1778)
						)
						(arc
							(start -0.2794 0.1778)
							(mid -0.249642 0.249642)
							(end -0.1778 0.2794)
						)
						(arc
							(start 0.1778 0.2794)
							(mid 0.249642 0.249642)
							(end 0.2794 0.1778)
						)
						(arc
							(start 0.2794 -0.1778)
							(mid 0.249642 -0.249642)
							(end 0.1778 -0.2794)
						)
					)
					(width 0)
					(fill yes)
				)
			)
		)
	)
)
